(kicad_pcb
	(version 20260206)
	(generator "pcbnew")
	(generator_version "10.0")
	(general
		(thickness 1.6)
		(legacy_teardrops no)
	)
	(paper "A4")
	(title_block
		(title "01162023_DA0F0TEBIF0_F0T_Expander_BD_F_brd_V02_OCP.brd")
		(comment 1 "Grand Teton / footprints 8789-8797 of 9728")
	)
	(layers
		(0 "F.Cu" signal "TOP")
		(4 "In1.Cu" signal "GND")
		(6 "In2.Cu" signal "VCC")
		(8 "In3.Cu" signal "VCC1")
		(10 "In4.Cu" signal "GND1")
		(12 "In5.Cu" signal "IN1")
		(14 "In6.Cu" signal "GND2")
		(16 "In7.Cu" signal "IN2")
		(18 "In8.Cu" signal "GND3")
		(20 "In9.Cu" signal "IN3")
		(22 "In10.Cu" signal "GND4")
		(24 "In11.Cu" signal "IN4")
		(26 "In12.Cu" signal "GND5")
		(28 "In13.Cu" signal "IN5")
		(30 "In14.Cu" signal "GND6")
		(32 "In15.Cu" signal "IN6")
		(34 "In16.Cu" signal "GND7")
		(2 "B.Cu" signal "BOTTOM")
		(9 "F.Adhes" user "F.Adhesive")
		(11 "B.Adhes" user "B.Adhesive")
		(13 "F.Paste" user "Package Geometry/Pastemask Top")
		(15 "B.Paste" user "Package Geometry/Pastemask Bottom")
		(5 "F.SilkS" user "Ref Des/Silkscreen Top")
		(7 "B.SilkS" user "Ref Des/Silkscreen Bottom")
		(1 "F.Mask" user "Board Geometry/Soldermask Top")
		(3 "B.Mask" user "Board Geometry/Soldermask Bottom")
		(17 "Dwgs.User" user "User.Drawings")
		(19 "Cmts.User" user "User.Comments")
		(21 "Eco1.User" user "User.Eco1")
		(23 "Eco2.User" user "User.Eco2")
		(25 "Edge.Cuts" user "Board Geometry/Outline")
		(27 "Margin" user)
		(31 "F.CrtYd" user "Package Geometry/Place Bound Top")
		(29 "B.CrtYd" user "Package Geometry/Place Bound Bottom")
		(35 "F.Fab" user "Ref Des/Assembly Top")
		(33 "B.Fab" user "Ref Des/Assembly Bottom")
	)
	(footprint ""
		(layer "B.Cu")
		(at 167.200072 -288.299906 90)
		(property "Reference" "C3094"
			(at 0 0 90)
			(layer "B.SilkS")
			(hide yes)
			(effects
				(font
					(size 1.27 1.27)
				)
				(justify mirror)
			)
		)
		(property "Value" ""
			(at 0 0 90)
			(layer "B.Fab")
			(effects
				(font
					(size 1.27 1.27)
				)
				(justify mirror)
			)
		)
		(duplicate_pad_numbers_are_jumpers no)
		(fp_line
			(start 0.299974 -0.150114)
			(end -0.299974 -0.150114)
			(stroke
				(width 0.1)
				(type default)
			)
			(layer "B.Fab")
		)
		(fp_line
			(start -0.299974 -0.150114)
			(end -0.299974 0.150114)
			(stroke
				(width 0.1)
				(type default)
			)
			(layer "B.Fab")
		)
		(fp_line
			(start 0.299974 0.150114)
			(end 0.299974 -0.150114)
			(stroke
				(width 0.1)
				(type default)
			)
			(layer "B.Fab")
		)
		(fp_line
			(start -0.299974 0.150114)
			(end 0.299974 0.150114)
			(stroke
				(width 0.1)
				(type default)
			)
			(layer "B.Fab")
		)
		(pad "1" smd rect
			(at 0.2667 0 270)
			(size 0.3048 0.381)
			(layers "B.Cu" "B.Mask" "B.Paste")
			(net "P1V25_PEX1")
		)
		(pad "2" smd rect
			(at -0.2667 0 270)
			(size 0.3048 0.381)
			(layers "B.Cu" "B.Mask" "B.Paste")
			(net "GND")
		)
	)
	(footprint ""
		(layer "B.Cu")
		(at 189.049914 -295.89984 180)
		(property "Reference" "C3149"
			(at 0 0 0)
			(layer "B.SilkS")
			(hide yes)
			(effects
				(font
					(size 1.27 1.27)
				)
				(justify mirror)
			)
		)
		(property "Value" ""
			(at 0 0 0)
			(layer "B.Fab")
			(effects
				(font
					(size 1.27 1.27)
				)
				(justify mirror)
			)
		)
		(duplicate_pad_numbers_are_jumpers no)
		(fp_line
			(start 0.299974 0.150114)
			(end 0.299974 -0.150114)
			(stroke
				(width 0.1)
				(type default)
			)
			(layer "B.Fab")
		)
		(fp_line
			(start 0.299974 -0.150114)
			(end -0.299974 -0.150114)
			(stroke
				(width 0.1)
				(type default)
			)
			(layer "B.Fab")
		)
		(fp_line
			(start -0.299974 0.150114)
			(end 0.299974 0.150114)
			(stroke
				(width 0.1)
				(type default)
			)
			(layer "B.Fab")
		)
		(fp_line
			(start -0.299974 -0.150114)
			(end -0.299974 0.150114)
			(stroke
				(width 0.1)
				(type default)
			)
			(layer "B.Fab")
		)
		(pad "1" smd rect
			(at 0.2667 0)
			(size 0.3048 0.381)
			(layers "B.Cu" "B.Mask" "B.Paste")
			(net "P1V25_SERDES_VDDPLL_PEX1")
		)
		(pad "2" smd rect
			(at -0.2667 0)
			(size 0.3048 0.381)
			(layers "B.Cu" "B.Mask" "B.Paste")
			(net "GND")
		)
	)
	(footprint ""
		(layer "B.Cu")
		(at 106.463846 -87.12327 180)
		(property "Reference" "C2671"
			(at 0 0 0)
			(layer "B.SilkS")
			(hide yes)
			(effects
				(font
					(size 1.27 1.27)
				)
				(justify mirror)
			)
		)
		(property "Value" ""
			(at 0 0 0)
			(layer "B.Fab")
			(effects
				(font
					(size 1.27 1.27)
				)
				(justify mirror)
			)
		)
		(duplicate_pad_numbers_are_jumpers no)
		(fp_line
			(start 0.7874 0.4064)
			(end 0.7874 -0.4064)
			(stroke
				(width 0.1524)
				(type default)
			)
			(layer "B.SilkS")
		)
		(fp_line
			(start 0.7874 -0.4064)
			(end -0.7874 -0.4064)
			(stroke
				(width 0.1524)
				(type default)
			)
			(layer "B.SilkS")
		)
		(fp_line
			(start -0.7874 0.4064)
			(end 0.7874 0.4064)
			(stroke
				(width 0.1524)
				(type default)
			)
			(layer "B.SilkS")
		)
		(fp_line
			(start -0.7874 -0.4064)
			(end -0.7874 0.4064)
			(stroke
				(width 0.1524)
				(type default)
			)
			(layer "B.SilkS")
		)
		(fp_line
			(start 0.67945 0.3048)
			(end 0.67945 -0.305054)
			(stroke
				(width 0.1)
				(type default)
			)
			(layer "B.Fab")
		)
		(fp_line
			(start 0.67945 -0.305054)
			(end 0.12065 -0.305054)
			(stroke
				(width 0.1)
				(type default)
			)
			(layer "B.Fab")
		)
		(fp_line
			(start 0.12065 0.3048)
			(end 0.67945 0.3048)
			(stroke
				(width 0.1)
				(type default)
			)
			(layer "B.Fab")
		)
		(fp_line
			(start 0.12065 0.2794)
			(end 0.12065 0.3048)
			(stroke
				(width 0.1)
				(type default)
			)
			(layer "B.Fab")
		)
		(fp_line
			(start 0.12065 -0.2794)
			(end -0.12065 -0.2794)
			(stroke
				(width 0.1)
				(type default)
			)
			(layer "B.Fab")
		)
		(fp_line
			(start 0.12065 -0.305054)
			(end 0.12065 -0.2794)
			(stroke
				(width 0.1)
				(type default)
			)
			(layer "B.Fab")
		)
		(fp_line
			(start -0.120396 0.3048)
			(end -0.120396 0.2794)
			(stroke
				(width 0.1)
				(type default)
			)
			(layer "B.Fab")
		)
		(fp_line
			(start -0.120396 0.2794)
			(end 0.12065 0.2794)
			(stroke
				(width 0.1)
				(type default)
			)
			(layer "B.Fab")
		)
		(fp_line
			(start -0.12065 -0.2794)
			(end -0.12065 -0.3048)
			(stroke
				(width 0.1)
				(type default)
			)
			(layer "B.Fab")
		)
		(fp_line
			(start -0.12065 -0.3048)
			(end -0.67945 -0.3048)
			(stroke
				(width 0.1)
				(type default)
			)
			(layer "B.Fab")
		)
		(fp_line
			(start -0.67945 0.3048)
			(end -0.120396 0.3048)
			(stroke
				(width 0.1)
				(type default)
			)
			(layer "B.Fab")
		)
		(fp_line
			(start -0.67945 -0.3048)
			(end -0.67945 0.3048)
			(stroke
				(width 0.1)
				(type default)
			)
			(layer "B.Fab")
		)
		(pad "1" smd circle
			(at 0.40005 0)
			(size 0 0)
			(layers "B.Cu" "B.Mask" "B.Paste")
			(net "P3V3_VDDAR_9ZXL0851_0_7")
		)
		(pad "2" smd circle
			(at -0.40005 0)
			(size 0 0)
			(layers "B.Cu" "B.Mask" "B.Paste")
			(net "GND")
		)
	)
	(footprint ""
		(layer "B.Cu")
		(at 382.895602 -243.39296)
		(property "Reference" "C2563"
			(at 0 0 0)
			(layer "B.SilkS")
			(hide yes)
			(effects
				(font
					(size 1.27 1.27)
				)
				(justify mirror)
			)
		)
		(property "Value" ""
			(at 0 0 0)
			(layer "B.Fab")
			(effects
				(font
					(size 1.27 1.27)
				)
				(justify mirror)
			)
		)
		(duplicate_pad_numbers_are_jumpers no)
		(fp_line
			(start -0.7874 -0.4064)
			(end -0.7874 0.4064)
			(stroke
				(width 0.1524)
				(type default)
			)
			(layer "B.SilkS")
		)
		(fp_line
			(start -0.7874 0.4064)
			(end 0.7874 0.4064)
			(stroke
				(width 0.1524)
				(type default)
			)
			(layer "B.SilkS")
		)
		(fp_line
			(start 0.7874 -0.4064)
			(end -0.7874 -0.4064)
			(stroke
				(width 0.1524)
				(type default)
			)
			(layer "B.SilkS")
		)
		(fp_line
			(start 0.7874 0.4064)
			(end 0.7874 -0.4064)
			(stroke
				(width 0.1524)
				(type default)
			)
			(layer "B.SilkS")
		)
		(fp_line
			(start -0.67945 -0.3048)
			(end -0.67945 0.3048)
			(stroke
				(width 0.1)
				(type default)
			)
			(layer "B.Fab")
		)
		(fp_line
			(start -0.67945 0.3048)
			(end -0.120396 0.3048)
			(stroke
				(width 0.1)
				(type default)
			)
			(layer "B.Fab")
		)
		(fp_line
			(start -0.12065 -0.3048)
			(end -0.67945 -0.3048)
			(stroke
				(width 0.1)
				(type default)
			)
			(layer "B.Fab")
		)
		(fp_line
			(start -0.12065 -0.2794)
			(end -0.12065 -0.3048)
			(stroke
				(width 0.1)
				(type default)
			)
			(layer "B.Fab")
		)
		(fp_line
			(start -0.120396 0.2794)
			(end 0.12065 0.2794)
			(stroke
				(width 0.1)
				(type default)
			)
			(layer "B.Fab")
		)
		(fp_line
			(start -0.120396 0.3048)
			(end -0.120396 0.2794)
			(stroke
				(width 0.1)
				(type default)
			)
			(layer "B.Fab")
		)
		(fp_line
			(start 0.12065 -0.305054)
			(end 0.12065 -0.2794)
			(stroke
				(width 0.1)
				(type default)
			)
			(layer "B.Fab")
		)
		(fp_line
			(start 0.12065 -0.2794)
			(end -0.12065 -0.2794)
			(stroke
				(width 0.1)
				(type default)
			)
			(layer "B.Fab")
		)
		(fp_line
			(start 0.12065 0.2794)
			(end 0.12065 0.3048)
			(stroke
				(width 0.1)
				(type default)
			)
			(layer "B.Fab")
		)
		(fp_line
			(start 0.12065 0.3048)
			(end 0.67945 0.3048)
			(stroke
				(width 0.1)
				(type default)
			)
			(layer "B.Fab")
		)
		(fp_line
			(start 0.67945 -0.305054)
			(end 0.12065 -0.305054)
			(stroke
				(width 0.1)
				(type default)
			)
			(layer "B.Fab")
		)
		(fp_line
			(start 0.67945 0.3048)
			(end 0.67945 -0.305054)
			(stroke
				(width 0.1)
				(type default)
			)
			(layer "B.Fab")
		)
		(pad "1" smd circle
			(at 0.40005 0 180)
			(size 0 0)
			(layers "B.Cu" "B.Mask" "B.Paste")
			(net "P3V3_AUX")
		)
		(pad "2" smd circle
			(at -0.40005 0 180)
			(size 0 0)
			(layers "B.Cu" "B.Mask" "B.Paste")
			(net "GND")
		)
	)
	(footprint ""
		(layer "B.Cu")
		(at 406.049988 -299.699934 -90)
		(property "Reference" "C1939"
			(at 0 0 90)
			(layer "B.SilkS")
			(hide yes)
			(effects
				(font
					(size 1.27 1.27)
				)
				(justify mirror)
			)
		)
		(property "Value" ""
			(at 0 0 90)
			(layer "B.Fab")
			(effects
				(font
					(size 1.27 1.27)
				)
				(justify mirror)
			)
		)
		(duplicate_pad_numbers_are_jumpers no)
		(fp_line
			(start -0.299974 0.150114)
			(end 0.299974 0.150114)
			(stroke
				(width 0.1)
				(type default)
			)
			(layer "B.Fab")
		)
		(fp_line
			(start 0.299974 0.150114)
			(end 0.299974 -0.150114)
			(stroke
				(width 0.1)
				(type default)
			)
			(layer "B.Fab")
		)
		(fp_line
			(start -0.299974 -0.150114)
			(end -0.299974 0.150114)
			(stroke
				(width 0.1)
				(type default)
			)
			(layer "B.Fab")
		)
		(fp_line
			(start 0.299974 -0.150114)
			(end -0.299974 -0.150114)
			(stroke
				(width 0.1)
				(type default)
			)
			(layer "B.Fab")
		)
		(pad "1" smd rect
			(at 0.2667 0 90)
			(size 0.3048 0.381)
			(layers "B.Cu" "B.Mask" "B.Paste")
			(net "P0V8_SERDES_VDDA_PEX3")
		)
		(pad "2" smd rect
			(at -0.2667 0 90)
			(size 0.3048 0.381)
			(layers "B.Cu" "B.Mask" "B.Paste")
			(net "GND")
		)
	)
	(footprint ""
		(layer "B.Cu")
		(at 226.546664 -208.78546 -90)
		(property "Reference" "R4894"
			(at 0 0 90)
			(layer "B.SilkS")
			(hide yes)
			(effects
				(font
					(size 1.27 1.27)
				)
				(justify mirror)
			)
		)
		(property "Value" ""
			(at 0 0 90)
			(layer "B.Fab")
			(effects
				(font
					(size 1.27 1.27)
				)
				(justify mirror)
			)
		)
		(duplicate_pad_numbers_are_jumpers no)
		(fp_line
			(start -0.7874 0.4064)
			(end 0.7874 0.4064)
			(stroke
				(width 0.1524)
				(type default)
			)
			(layer "B.SilkS")
		)
		(fp_line
			(start 0.7874 0.4064)
			(end 0.7874 -0.4064)
			(stroke
				(width 0.1524)
				(type default)
			)
			(layer "B.SilkS")
		)
		(fp_line
			(start -0.7874 -0.4064)
			(end -0.7874 0.4064)
			(stroke
				(width 0.1524)
				(type default)
			)
			(layer "B.SilkS")
		)
		(fp_line
			(start 0.7874 -0.4064)
			(end -0.7874 -0.4064)
			(stroke
				(width 0.1524)
				(type default)
			)
			(layer "B.SilkS")
		)
		(fp_line
			(start -0.67945 0.3048)
			(end -0.120396 0.3048)
			(stroke
				(width 0.1)
				(type default)
			)
			(layer "B.Fab")
		)
		(fp_line
			(start -0.120396 0.3048)
			(end -0.120396 0.2794)
			(stroke
				(width 0.1)
				(type default)
			)
			(layer "B.Fab")
		)
		(fp_line
			(start 0.12065 0.3048)
			(end 0.67945 0.3048)
			(stroke
				(width 0.1)
				(type default)
			)
			(layer "B.Fab")
		)
		(fp_line
			(start 0.67945 0.3048)
			(end 0.67945 -0.305054)
			(stroke
				(width 0.1)
				(type default)
			)
			(layer "B.Fab")
		)
		(fp_line
			(start -0.120396 0.2794)
			(end 0.12065 0.2794)
			(stroke
				(width 0.1)
				(type default)
			)
			(layer "B.Fab")
		)
		(fp_line
			(start 0.12065 0.2794)
			(end 0.12065 0.3048)
			(stroke
				(width 0.1)
				(type default)
			)
			(layer "B.Fab")
		)
		(fp_line
			(start -0.12065 -0.2794)
			(end -0.12065 -0.3048)
			(stroke
				(width 0.1)
				(type default)
			)
			(layer "B.Fab")
		)
		(fp_line
			(start 0.12065 -0.2794)
			(end -0.12065 -0.2794)
			(stroke
				(width 0.1)
				(type default)
			)
			(layer "B.Fab")
		)
		(fp_line
			(start -0.67945 -0.3048)
			(end -0.67945 0.3048)
			(stroke
				(width 0.1)
				(type default)
			)
			(layer "B.Fab")
		)
		(fp_line
			(start -0.12065 -0.3048)
			(end -0.67945 -0.3048)
			(stroke
				(width 0.1)
				(type default)
			)
			(layer "B.Fab")
		)
		(fp_line
			(start 0.12065 -0.305054)
			(end 0.12065 -0.2794)
			(stroke
				(width 0.1)
				(type default)
			)
			(layer "B.Fab")
		)
		(fp_line
			(start 0.67945 -0.305054)
			(end 0.12065 -0.305054)
			(stroke
				(width 0.1)
				(type default)
			)
			(layer "B.Fab")
		)
		(pad "1" smd circle
			(at 0.40005 0 90)
			(size 0 0)
			(layers "B.Cu" "B.Mask" "B.Paste")
			(net "JTAG_BIC_TMS_R")
		)
		(pad "2" smd circle
			(at -0.40005 0 90)
			(size 0 0)
			(layers "B.Cu" "B.Mask" "B.Paste")
			(net "JTAG_BIC_TMS")
		)
	)
	(footprint ""
		(layer "B.Cu")
		(at 340.641432 -303.649634 -90)
		(property "Reference" "PC149"
			(at 0 0 90)
			(layer "B.SilkS")
			(hide yes)
			(effects
				(font
					(size 1.27 1.27)
				)
				(justify mirror)
			)
		)
		(property "Value" ""
			(at 0 0 90)
			(layer "B.Fab")
			(effects
				(font
					(size 1.27 1.27)
				)
				(justify mirror)
			)
		)
		(duplicate_pad_numbers_are_jumpers no)
		(fp_line
			(start -1.524 0.762)
			(end 1.524 0.762)
			(stroke
				(width 0.1524)
				(type default)
			)
			(layer "B.SilkS")
		)
		(fp_line
			(start 1.524 0.762)
			(end 1.524 -0.762)
			(stroke
				(width 0.1524)
				(type default)
			)
			(layer "B.SilkS")
		)
		(fp_line
			(start -1.524 -0.762)
			(end -1.524 0.762)
			(stroke
				(width 0.1524)
				(type default)
			)
			(layer "B.SilkS")
		)
		(fp_line
			(start 1.524 -0.762)
			(end -1.524 -0.762)
			(stroke
				(width 0.1524)
				(type default)
			)
			(layer "B.SilkS")
		)
		(fp_line
			(start -1.1049 0.724916)
			(end -1.1049 -0.724916)
			(stroke
				(width 0.1)
				(type default)
			)
			(layer "B.Fab")
		)
		(fp_line
			(start 1.1049 0.724916)
			(end -1.1049 0.724916)
			(stroke
				(width 0.1)
				(type default)
			)
			(layer "B.Fab")
		)
		(fp_line
			(start -1.1049 -0.724916)
			(end 1.1049 -0.724916)
			(stroke
				(width 0.1)
				(type default)
			)
			(layer "B.Fab")
		)
		(fp_line
			(start 1.1049 -0.724916)
			(end 1.1049 0.724916)
			(stroke
				(width 0.1)
				(type default)
			)
			(layer "B.Fab")
		)
		(pad "1" smd rect
			(at 0.889 0 270)
			(size 1.016 1.27)
			(layers "B.Cu" "B.Mask" "B.Paste")
			(net "P0V8_PEX2")
		)
		(pad "2" smd rect
			(at -0.889 0 270)
			(size 1.016 1.27)
			(layers "B.Cu" "B.Mask" "B.Paste")
			(net "GND")
		)
	)
	(footprint ""
		(layer "B.Cu")
		(at 175.749966 -290.199826 90)
		(property "Reference" "C1483"
			(at 0 0 90)
			(layer "B.SilkS")
			(hide yes)
			(effects
				(font
					(size 1.27 1.27)
				)
				(justify mirror)
			)
		)
		(property "Value" ""
			(at 0 0 90)
			(layer "B.Fab")
			(effects
				(font
					(size 1.27 1.27)
				)
				(justify mirror)
			)
		)
		(duplicate_pad_numbers_are_jumpers no)
		(fp_line
			(start 0.299974 -0.150114)
			(end -0.299974 -0.150114)
			(stroke
				(width 0.1)
				(type default)
			)
			(layer "B.Fab")
		)
		(fp_line
			(start -0.299974 -0.150114)
			(end -0.299974 0.150114)
			(stroke
				(width 0.1)
				(type default)
			)
			(layer "B.Fab")
		)
		(fp_line
			(start 0.299974 0.150114)
			(end 0.299974 -0.150114)
			(stroke
				(width 0.1)
				(type default)
			)
			(layer "B.Fab")
		)
		(fp_line
			(start -0.299974 0.150114)
			(end 0.299974 0.150114)
			(stroke
				(width 0.1)
				(type default)
			)
			(layer "B.Fab")
		)
		(pad "1" smd rect
			(at 0.2667 0 270)
			(size 0.3048 0.381)
			(layers "B.Cu" "B.Mask" "B.Paste")
			(net "P0V8_SERDES_VDDA_PEX1")
		)
		(pad "2" smd rect
			(at -0.2667 0 270)
			(size 0.3048 0.381)
			(layers "B.Cu" "B.Mask" "B.Paste")
			(net "GND")
		)
	)
	(footprint ""
		(layer "B.Cu")
		(at 355.962712 -321.15125 -90)
		(property "Reference" "R6538"
			(at 0 0 90)
			(layer "B.SilkS")
			(hide yes)
			(effects
				(font
					(size 1.27 1.27)
				)
				(justify mirror)
			)
		)
		(property "Value" ""
			(at 0 0 90)
			(layer "B.Fab")
			(effects
				(font
					(size 1.27 1.27)
				)
				(justify mirror)
			)
		)
		(duplicate_pad_numbers_are_jumpers no)
		(fp_line
			(start -0.7874 0.4064)
			(end 0.7874 0.4064)
			(stroke
				(width 0.1524)
				(type default)
			)
			(layer "B.SilkS")
		)
		(fp_line
			(start 0.7874 0.4064)
			(end 0.7874 -0.4064)
			(stroke
				(width 0.1524)
				(type default)
			)
			(layer "B.SilkS")
		)
		(fp_line
			(start -0.7874 -0.4064)
			(end -0.7874 0.4064)
			(stroke
				(width 0.1524)
				(type default)
			)
			(layer "B.SilkS")
		)
		(fp_line
			(start 0.7874 -0.4064)
			(end -0.7874 -0.4064)
			(stroke
				(width 0.1524)
				(type default)
			)
			(layer "B.SilkS")
		)
		(fp_line
			(start -0.67945 0.3048)
			(end -0.120396 0.3048)
			(stroke
				(width 0.1)
				(type default)
			)
			(layer "B.Fab")
		)
		(fp_line
			(start -0.120396 0.3048)
			(end -0.120396 0.2794)
			(stroke
				(width 0.1)
				(type default)
			)
			(layer "B.Fab")
		)
		(fp_line
			(start 0.12065 0.3048)
			(end 0.67945 0.3048)
			(stroke
				(width 0.1)
				(type default)
			)
			(layer "B.Fab")
		)
		(fp_line
			(start 0.67945 0.3048)
			(end 0.67945 -0.305054)
			(stroke
				(width 0.1)
				(type default)
			)
			(layer "B.Fab")
		)
		(fp_line
			(start -0.120396 0.2794)
			(end 0.12065 0.2794)
			(stroke
				(width 0.1)
				(type default)
			)
			(layer "B.Fab")
		)
		(fp_line
			(start 0.12065 0.2794)
			(end 0.12065 0.3048)
			(stroke
				(width 0.1)
				(type default)
			)
			(layer "B.Fab")
		)
		(fp_line
			(start -0.12065 -0.2794)
			(end -0.12065 -0.3048)
			(stroke
				(width 0.1)
				(type default)
			)
			(layer "B.Fab")
		)
		(fp_line
			(start 0.12065 -0.2794)
			(end -0.12065 -0.2794)
			(stroke
				(width 0.1)
				(type default)
			)
			(layer "B.Fab")
		)
		(fp_line
			(start -0.67945 -0.3048)
			(end -0.67945 0.3048)
			(stroke
				(width 0.1)
				(type default)
			)
			(layer "B.Fab")
		)
		(fp_line
			(start -0.12065 -0.3048)
			(end -0.67945 -0.3048)
			(stroke
				(width 0.1)
				(type default)
			)
			(layer "B.Fab")
		)
		(fp_line
			(start 0.12065 -0.305054)
			(end 0.12065 -0.2794)
			(stroke
				(width 0.1)
				(type default)
			)
			(layer "B.Fab")
		)
		(fp_line
			(start 0.67945 -0.305054)
			(end 0.12065 -0.305054)
			(stroke
				(width 0.1)
				(type default)
			)
			(layer "B.Fab")
		)
		(pad "1" smd circle
			(at 0.40005 0 90)
			(size 0 0)
			(layers "B.Cu" "B.Mask" "B.Paste")
			(net "P0V8_SERDES_VDDA_PEX3")
		)
		(pad "2" smd circle
			(at -0.40005 0 90)
			(size 0 0)
			(layers "B.Cu" "B.Mask" "B.Paste")
			(net "P0V8_SERDES_VDDA_PEX3_C3")
		)
	)
)
